# S9S_MB_2U (Grand Teton) — schematic parts with pin connectivity, parts 5445–5592 of 6093; source: Cadence DE-HDL packaged netlist (pstxprt.dat, pstxnet.dat, pstchip.dat)

R4204  Q_RES  1K 1% EMPTY  pkg 0402LF  page 170 : 1 = P3V3_AUX ; 2 = U271_1_ADD0
R4205  Q_RES  1K 1% CHIP  pkg 0402LF  page 170 : 1 = U271_1_ADD0 ; 2 = GND
R4206  Q_RES  1K 1% EMPTY  pkg 0402LF  page 170 : 1 = P3V3_AUX ; 2 = U270_0_ADD0
R4207  Q_RES  1K 1% CHIP  pkg 0402LF  page 170 : 1 = U270_0_ADD0 ; 2 = GND
R4208  Q_RES  200K 1% EMPTY  pkg 0402LF  page 170 : 1 = P3V3_AUX ; 2 = FM_THERMAL_ALERT_N
R4209  Q_RES  200K 1% EMPTY  pkg 0402LF  page 170 : 1 = P3V3_AUX ; 2 = FM_THERMAL_ALERT_N
R4210  Q_RES  200K 1% EMPTY  pkg 0402LF  page 170 : 1 = P3V3_AUX ; 2 = FM_THERMAL_ALERT_N
R4211  Q_RES  200K 1% CHIP  pkg 0402LF  page 170 : 1 = P3V3_AUX ; 2 = FM_THERMAL_ALERT_N
R4212  Q_RES  0 5% CHIP  pkg 0402LF  page 170 : 1 = FM_THERMAL_ALERT_N ; 2 = FM_LM75_3_ALERT_N
R4213  Q_RES  0 5% CHIP  pkg 0402LF  page 170 : 1 = FM_THERMAL_ALERT_N ; 2 = FM_LM75_2_ALERT_N
R4214  Q_RES  0 5% CHIP  pkg 0402LF  page 170 : 1 = FM_THERMAL_ALERT_N ; 2 = FM_G751_1_ALERT_N
R4215  Q_RES  0 5% CHIP  pkg 0402LF  page 170 : 1 = FM_THERMAL_ALERT_N ; 2 = FM_G751_0_ALERT_N
R4216  Q_RES  0 5% CHIP  pkg 0402LF  page 266 : 1 = FM_PVCCFA_EHV_FIVRA_CPU0_EN ; 2 = PVCCFA_EHV_FIVRA_CPU0_EN_R
R4259  Q_RES  33.2 1% CHIP  pkg 0402LF  page 214 : 1 = FM_THERMAL_ALERT_N ; 2 = FM_THERMAL_ALERT_R_N
R4260  Q_RES  240 1% EMPTY  pkg 0402LF  page 119 : 1 = PVNN_TERM_CPU0 ; 2 = PD_CPU1_BIST_ENABLE
R4261  Q_RES  240 1% EMPTY  pkg 0402LF  page 119 : 1 = PD_CPU1_BIST_ENABLE ; 2 = GND
R4262  Q_RES  240 1% EMPTY  pkg 0402LF  page 119 : 1 = PVNN_TERM_CPU0 ; 2 = PD_CPU0_BIST_ENABLE
R4263  Q_RES  240 1% EMPTY  pkg 0402LF  page 119 : 1 = PD_CPU0_BIST_ENABLE ; 2 = GND
R4264  Q_RES  4.7K 5% CHIP  pkg 0402LF  page 246 : 1 = P3V3_AUX ; 2 = PWRGD_P3V3_AUX_PDB_BUF_R
R4265  Q_RES  4.7K 5% EMPTY  pkg 0402LF  page 246 : 1 = PWRGD_P3V3_AUX_PDB_BUF_R ; 2 = GND
R4266  Q_RES  33.2 1% CHIP  pkg 0402LF  page 246 : 1 = PWRGD_P3V3_AUX_PDB_BUF_R ; 2 = PWRGD_P3V3_AUX_PDB_BUF
R4267  Q_RES  33.2 1% CHIP  pkg 0402LF  page 222 : 1 = PWRGD_P3V3_AUX ; 2 = PWRGD_P3V3_AUX_PDB
R4268  Q_RES  0 5% CHIP  pkg 0402LF  page 246 : 1 = PWRGD_P3V3_AUX_PDB ; 2 = PWRGD_P3V3_AUX_PDB_R
R4269  Q_RES  2.2K 5% EMPTY  pkg 0402LF  page 233 : 1 = P3V3_AUX ; 2 = SMB_VR_SENSOR_3V3AUX_SCL
R4270  Q_RES  2.2K 5% EMPTY  pkg 0402LF  page 233 : 1 = P3V3_AUX ; 2 = SMB_VR_SENSOR_3V3AUX_SDA
R4273  Q_RES  1K 1% EMPTY  pkg 0402LF  page 169 : 1 = P3V3_AUX ; 2 = FM_USB3_1_FGB
R4274  Q_RES  1K 1% EMPTY  pkg 0402LF  page 169 : 1 = FM_USB3_1_FGB ; 2 = GND
R4275  Q_RES  1K 1% EMPTY  pkg 0402LF  page 169 : 1 = P3V3_AUX ; 2 = FM_USB3_1_EQA
R4276  Q_RES  68K 1% CHIP  pkg 0402LF  page 169 : 1 = FM_USB3_1_EQA ; 2 = GND
R4279  Q_RES  1K 1% EMPTY  pkg 0402LF  page 169 : 1 = P3V3_AUX ; 2 = FM_USB3_1_FGA
R4280  Q_RES  1K 1% EMPTY  pkg 0402LF  page 169 : 1 = FM_USB3_1_FGA ; 2 = GND
R4281  Q_RES  1K 1% EMPTY  pkg 0402LF  page 169 : 1 = P3V3_AUX ; 2 = FM_USB3_1_EQB
R4282  Q_RES  68K 1% CHIP  pkg 0402LF  page 169 : 1 = FM_USB3_1_EQB ; 2 = GND
R4284  Q_RES  1K 1% EMPTY  pkg 0402LF  page 169 : 1 = P3V3_AUX ; 2 = FM_USB3_1_SWB
R4285  Q_RES  1K 1% EMPTY  pkg 0402LF  page 169 : 1 = FM_USB3_1_SWB ; 2 = GND
R4287  Q_RES  1K 1% EMPTY  pkg 0402LF  page 169 : 1 = P3V3_AUX ; 2 = FM_USB3_1_SWA
R4288  Q_RES  1K 1% EMPTY  pkg 0402LF  page 169 : 1 = FM_USB3_1_SWA ; 2 = GND
R4289  Q_RES  4.7K 1% EMPTY  pkg 0402LF  page 169 : 1 = P3V3_AUX ; 2 = FM_USB3_1_RXDET_EN
R4290  Q_RES  4.7K 1% EMPTY  pkg 0402LF  page 169 : 1 = FM_USB3_1_RXDET_EN ; 2 = GND
R4291  Q_RES  4.7K 1% EMPTY  pkg 0402LF  page 169 : 1 = P3V3_AUX ; 2 = FM_USB3_1_EN_N
R4292  Q_RES  4.7K 1% EMPTY  pkg 0402LF  page 169 : 1 = FM_USB3_1_EN_N ; 2 = GND
R4293  Q_RES  100 1% CHIP  pkg 0402LF  page 122 : 1 = H_CPU0_MEMHOT_IN_LVC1_R1_N ; 2 = H_CPU0_MEMHOT_IN_LVC1_N
R4294  Q_RES  100 1% CHIP  pkg 0402LF  page 122 : 1 = H_CPU1_MEMHOT_IN_LVC1_R1_N ; 2 = H_CPU1_MEMHOT_IN_LVC1_N
R4295  Q_RES  100 1% CHIP  pkg 0402LF  page 124 : 1 = PWRGD_DRAMPWRGD_CPU0_AB_LVC1_R2 ; 2 = PWRGD_DRAMPWRGD_CPU0_AB_LVC1_R
R4296  Q_RES  100 1% CHIP  pkg 0402LF  page 124 : 1 = PWRGD_DRAMPWRGD_CPU0_CD_LVC1_R2 ; 2 = PWRGD_DRAMPWRGD_CPU0_CD_LVC1_R
R4297  Q_RES  100 1% CHIP  pkg 0402LF  page 124 : 1 = PWRGD_DRAMPWRGD_CPU0_EF_LVC1_R2 ; 2 = PWRGD_DRAMPWRGD_CPU0_EF_LVC1_R
R4298  Q_RES  100 1% CHIP  pkg 0402LF  page 124 : 1 = PWRGD_DRAMPWRGD_CPU0_GH_LVC1_R2 ; 2 = PWRGD_DRAMPWRGD_CPU0_GH_LVC1_R
R4299  Q_RES  100 1% CHIP  pkg 0402LF  page 125 : 1 = PWRGD_DRAMPWRGD_CPU1_AB_LVC1_R2 ; 2 = PWRGD_DRAMPWRGD_CPU1_AB_LVC1_R
R4300  Q_RES  100 1% CHIP  pkg 0402LF  page 125 : 1 = PWRGD_DRAMPWRGD_CPU1_CD_LVC1_R2 ; 2 = PWRGD_DRAMPWRGD_CPU1_CD_LVC1_R
R4301  Q_RES  100 1% CHIP  pkg 0402LF  page 125 : 1 = PWRGD_DRAMPWRGD_CPU1_EF_LVC1_R2 ; 2 = PWRGD_DRAMPWRGD_CPU1_EF_LVC1_R
R4302  Q_RES  100 1% CHIP  pkg 0402LF  page 125 : 1 = PWRGD_DRAMPWRGD_CPU1_GH_LVC1_R2 ; 2 = PWRGD_DRAMPWRGD_CPU1_GH_LVC1_R
R4303  Q_RES  22 1% CHIP  pkg 0402LF  page 179 : 1 = CLK_100M_E1S_0_R_DP ; 2 = CLK_100M_E1S_0_DP
R4304  Q_RES  22 1% CHIP  pkg 0402LF  page 179 : 1 = CLK_100M_E1S_0_R_DN ; 2 = CLK_100M_E1S_0_DN
R4305  Q_RES  0 5% CHIP  pkg 0402LF  page 179 : 1 = CLK_100M_PE_M2_0_R_DP ; 2 = CLK_100M_PE_M2_0_DP
R4306  Q_RES  0 5% CHIP  pkg 0402LF  page 179 : 1 = CLK_100M_PE_M2_0_R_DN ; 2 = CLK_100M_PE_M2_0_DN
R4388  Q_RES  150 1% CHIP  pkg 0402LF  page 225 : 1 = PVNN_TERM_CPU0 ; 2 = H_CPU_ERR1_LVC1_R_N
R4389  Q_RES  150 1% CHIP  pkg 0402LF  page 225 : 1 = PVNN_TERM_CPU0 ; 2 = H_CPU_ERR2_LVC1_R_N
R4390  Q_RES  150 1% CHIP  pkg 0402LF  page 225 : 1 = PVNN_TERM_CPU0 ; 2 = H_CPU_ERR0_LVC1_R_N
R4391  Q_RES  150 1% CHIP  pkg 0402LF  page 225 : 1 = PD_GTL2014_ERROR_B0 ; 2 = GND
R4392  Q_RES  33.2 1% CHIP  pkg 0402LF  page 225 : 1 = H_CPU_ERR0_LVC2_R_N ; 2 = H_CPU_ERR0_PCH_R_N
R4393  Q_RES  33.2 1% CHIP  pkg 0402LF  page 225 : 1 = H_CPU_ERR1_LVC2_R_N ; 2 = H_CPU_ERR1_PCH_R_N
R4394  Q_RES  33.2 1% CHIP  pkg 0402LF  page 225 : 1 = H_CPU_ERR2_LVC2_R_N ; 2 = H_CPU_ERR2_PCH_R_N
R4395  Q_RES  100 1% CHIP  pkg 0402LF  page 121 : 1 = PVNN_TERM_CPU0 ; 2 = H_CPU0_THERMTRIP_LVC1_R_N
R4396  Q_RES  100 1% CHIP  pkg 0402LF  page 121 : 1 = PVNN_TERM_CPU1 ; 2 = H_CPU1_THERMTRIP_LVC1_R_N
R4397  Q_RES  1.5K 1% CHIP  pkg 0402LF  page 121 : 1 = H_CPU0_THERMTRIP_N ; 2 = H_CPU0_THERMTRIP_R_N
R4398  Q_RES  1.5K 1% CHIP  pkg 0402LF  page 121 : 1 = H_CPU1_THERMTRIP_N ; 2 = H_CPU1_THERMTRIP_R_N
R4399  Q_RES  33.2 1% CHIP  pkg 0402LF  page 121 : 1 = H_CPU0_THERMTRIP_VT_N ; 2 = H_CPU0_THERMTRIP_LVC1_N
R4400  Q_RES  33.2 1% CHIP  pkg 0402LF  page 121 : 1 = H_CPU1_THERMTRIP_VT_N ; 2 = H_CPU1_THERMTRIP_LVC1_N
R4401  Q_RES  100 1% CHIP  pkg 0402LF  page 122 : 1 = PVNN_TERM_CPU0 ; 2 = H_CPU0_MEMHOT_OUT_LVC1_R_N
R4402  Q_RES  100 1% CHIP  pkg 0402LF  page 122 : 1 = PVNN_TERM_CPU1 ; 2 = H_CPU1_MEMHOT_OUT_LVC1_R_N
R4403  Q_RES  1.5K 1% CHIP  pkg 0402LF  page 122 : 1 = H_CPU0_MEMHOT_OUT ; 2 = H_CPU0_MEMHOT_OUT_R
R4404  Q_RES  1.5K 1% CHIP  pkg 0402LF  page 122 : 1 = H_CPU1_MEMHOT_OUT ; 2 = H_CPU1_MEMHOT_OUT_R
R4405  Q_RES  4.75K 1% CHIP  pkg 0402LF  page 122 : 1 = P3V3 ; 2 = H_CPU0_MEMHOT_OUT_VT_N
R4406  Q_RES  4.75K 1% CHIP  pkg 0402LF  page 122 : 1 = P3V3 ; 2 = H_CPU1_MEMHOT_OUT_VT_N
R4407  Q_RES  33.2 1% CHIP  pkg 0402LF  page 122 : 1 = H_CPU0_MEMHOT_OUT_VT_N ; 2 = H_CPU0_MEMHOT_OUT_LVC1_N
R4408  Q_RES  33.2 1% CHIP  pkg 0402LF  page 122 : 1 = H_CPU1_MEMHOT_OUT_VT_N ; 2 = H_CPU1_MEMHOT_OUT_LVC1_N
R4409  Q_RES  1.5K 1% CHIP  pkg 0402LF  page 123 : 1 = H_CPU0_MEMTRIP ; 2 = H_CPU0_MEMTRIP_R
R4410  Q_RES  1.5K 1% CHIP  pkg 0402LF  page 123 : 1 = H_CPU1_MEMTRIP ; 2 = H_CPU1_MEMTRIP_R
R4411  Q_RES  4.75K 1% CHIP  pkg 0402LF  page 123 : 1 = P3V3 ; 2 = H_CPU0_MEMTRIP_VT_N
R4412  Q_RES  4.75K 1% CHIP  pkg 0402LF  page 123 : 1 = P3V3 ; 2 = H_CPU1_MEMTRIP_VT_N
R4413  Q_RES  33.2 1% CHIP  pkg 0402LF  page 123 : 1 = H_CPU0_MEMTRIP_VT_N ; 2 = H_CPU0_MEMTRIP_LVC1_N
R4414  Q_RES  33.2 1% CHIP  pkg 0402LF  page 123 : 1 = H_CPU1_MEMTRIP_VT_N ; 2 = H_CPU1_MEMTRIP_LVC1_N
R4419  Q_RES  49.9 1% EMPTY  pkg 0402LF  page 152 : 1 = USB2_HOST_BMC_B_DP ; 2 = GND
R4420  Q_RES  49.9 1% EMPTY  pkg 0402LF  page 152 : 1 = USB2_HOST_BMC_B_DN ; 2 = GND
R4448  Q_RES  10K 1% EMPTY  pkg 0402LF  page 196 : 1 = P3V3_AUX ; 2 = USB_HUB_2_PSELF
R4449  Q_RES  10K 1% EMPTY  pkg 0402LF  page 196 : 1 = USB_HUB_2_PSELF ; 2 = GND
R4450  Q_RES  0 5% EMPTY  pkg 0402LF  page 196 : 1 = P3V3_AUX ; 2 = P3V3_AUX_USB_HUB_2
R4451  Q_RES  33.2 1% EMPTY  pkg 0402LF  page 196 : 1 = RST_USB_HUB_N ; 2 = RST_USB_HUB_2_R_N
R4452  Q_RES  10K 1% EMPTY  pkg 0402LF  page 196 : 1 = P3V3_AUX ; 2 = RST_USB_HUB_2_R_N
R4453  Q_RES  47K 0.1% EMPTY  pkg 0402LF  page 196 : 1 = GND ; 2 = RST_USB_HUB_2_R_N
R4454  Q_RES  0 5% EMPTY  pkg 0402LF  page 196 : 1 = USB2_HUB_2_EXT_DP ; 2 = USB2_HUB_2_BUF_EXT_R_DP
R4455  Q_RES  0 5% EMPTY  pkg 0402LF  page 196 : 1 = USB2_HUB_2_EXT_DN ; 2 = USB2_HUB_2_BUF_EXT_R_DN
R4456  Q_RES  10K 1% EMPTY  pkg 0402LF  page 196 : 1 = P3V3_AUX ; 2 = USB_HUB_2_OVCUR1
R4457  Q_RES  10K 1% EMPTY  pkg 0402LF  page 196 : 1 = P3V3_AUX ; 2 = USB_HUB_2_OVCUR2
R4458  Q_RES  10K 1% EMPTY  pkg 0402LF  page 196 : 1 = P3V3_AUX ; 2 = USB_HUB_2_OVCUR3
R4459  Q_RES  10K 1% EMPTY  pkg 0402LF  page 196 : 1 = P3V3_AUX ; 2 = USB_HUB_2_OVCUR4
R4460  Q_RES  0 5% CHIP  pkg 0402LF  page 196 : 1 = USB2_HOST_PCH_0_DP ; 2 = USB2_HUB_2_BUF_EXT_R_DP
R4461  Q_RES  0 5% CHIP  pkg 0402LF  page 196 : 1 = USB2_HOST_PCH_0_DN ; 2 = USB2_HUB_2_BUF_EXT_R_DN
R4462  Q_RES  0 5% EMPTY  pkg 0402LF  page 196 : 1 = P3V3_AUX_USB_HUB_2 ; 2 = USB_HUB_2_DVDD
R4463  Q_RES  680 1% EMPTY  pkg 0402LF  page 196 : 1 = USB_HUB_2_RREF ; 2 = GND
R4464  Q_RES  100K 1% EMPTY  pkg 0402LF  page 196 : 1 = USB_HUB_2_PGANG ; 2 = GND
R4465  Q_RES  3.9K 5% EMPTY  pkg 0402LF  page 196 : 1 = PD_USB_HUB_2_EQ ; 2 = GND
R4466  Q_RES  0 5% EMPTY  pkg 0402LF  page 196 : 1 = USB_HUB_2_TEST ; 2 = GND
R4467  Q_RES  0 5% CHIP  pkg 0402LF  page 196 : 1 = USB2_HUB_2_BUF_EXT_R_DP ; 2 = USB2_HUB_2_BUF_EXT_DP
R4468  Q_RES  0 5% CHIP  pkg 0402LF  page 196 : 1 = USB2_HUB_2_BUF_EXT_R_DN ; 2 = USB2_HUB_2_BUF_EXT_DN
R4471  Q_RES  0 5% EMPTY  pkg 0402LF  page 196 : 1 = USB2_PCH_0_R_DP ; 2 = USB2_0_DP
R4472  Q_RES  0 5% EMPTY  pkg 0402LF  page 196 : 1 = USB2_PCH_0_R_DN ; 2 = USB2_0_DN
R4473  Q_RES  0 5% CHIP  pkg 0402LF  page 196 : 1 = USB2_0_DP ; 2 = USB2_HOST_PCH_0_DP
R4474  Q_RES  0 5% CHIP  pkg 0402LF  page 196 : 1 = USB2_0_DN ; 2 = USB2_HOST_PCH_0_DN
R4475  Q_RES  1 1% CHIP  pkg 0603LF  page 211 : 1 = P3V3_9ZXL045 ; 2 = P3V3_9ZXL045_VDDR
R4476  Q_RES  49.9 1% CHIP  pkg 0402LF  page 211 : 1 = FM_PLD_CLKS_DEV_EN ; 2 = FM_9ZXL045_DEV_EN
R4477  Q_RES  33.2 1% CHIP  pkg 0402LF  page 211 : 1 = FM_9ZXL045_0_OE_N ; 2 = CLK_SWB_BUF2_OE_N
R4478  Q_RES  33.2 1% CHIP  pkg 0402LF  page 211 : 1 = FM_9ZXL045_1_OE_N ; 2 = CLK_GPU_1_OE_N
R4479  Q_RES  33.2 1% CHIP  pkg 0402LF  page 211 : 1 = FM_9ZXL045_2_OE_N ; 2 = CLK_GPU_2_OE_N
R4480  Q_RES  33.2 1% CHIP  pkg 0402LF  page 237 : 1 = SMB_HOST_CLK_BUF_ISO_3V3AUX_SCL ; 2 = SMB_HOST_9ZXL045_3V3AUX_SCL
R4481  Q_RES  33.2 1% CHIP  pkg 0402LF  page 237 : 1 = SMB_HOST_CLK_BUF_ISO_3V3AUX_SDA ; 2 = SMB_HOST_9ZXL045_3V3AUX_SDA
R4482  Q_RES  49.9 1% EMPTY  pkg 0402LF  page 152 : 1 = USB2_HOST_BMC_B_BUF_DP ; 2 = GND
R4483  Q_RES  49.9 1% EMPTY  pkg 0402LF  page 152 : 1 = USB2_HOST_BMC_B_BUF_DN ; 2 = GND
R4486  Q_RES  49.9 1% EMPTY  pkg 0402LF  page 196 : 1 = USB2_HOST_PCH_0_DP ; 2 = GND
R4487  Q_RES  49.9 1% EMPTY  pkg 0402LF  page 196 : 1 = USB2_HOST_PCH_0_DN ; 2 = GND
R4489  Q_RES  4.75K 1% CHIP  pkg 0402LF  page 211 : 1 = P3V3 ; 2 = CLK_9ZXL045_SADR0
R4490  Q_RES  4.75K 1% EMPTY  pkg 0402LF  page 211 : 1 = CLK_9ZXL045_SADR0 ; 2 = GND
R4491  Q_RES  10K 1% CHIP  pkg 0402LF  page 211 : 1 = P3V3 ; 2 = CLK_9ZXL045_HIBW
R4492  Q_RES  10K 1% CHIP  pkg 0402LF  page 211 : 1 = CLK_9ZXL045_HIBW ; 2 = GND
R4493  Q_RES  1 1% CHIP  pkg 0603LF  page 211 : 1 = P3V3_9ZXL045 ; 2 = P3V3_9ZXL045_VDDA
R4494  Q_RES  10K 1% CHIP  pkg 0402LF  page 211 : 1 = FM_9ZXL045_3_OE_N ; 2 = P3V3
R4495  Q_RES  33.2 1% CHIP  pkg 0402LF  page 213 : 1 = OCP_SFF_CLK_OE_R_N ; 2 = OCP_SFF_CLK_OE_N
R4496  Q_RES  33.2 1% CHIP  pkg 0402LF  page 237 : 1 = SMB_HOST_CLK_BUF_ISO_3V3AUX_SCL ; 2 = SMB_HOST_DB2000_3V3AUX_SCL
R4497  Q_RES  33.2 1% CHIP  pkg 0402LF  page 237 : 1 = SMB_HOST_CLK_BUF_ISO_3V3AUX_SDA ; 2 = SMB_HOST_DB2000_3V3AUX_SDA
R4498  Q_RES  4.7K 5% CHIP  pkg 0402LF  page 237 : 1 = P3V3 ; 2 = SMB_HOST_CLK_BUF_ISO_3V3AUX_S_1
R4499  Q_RES  4.7K 5% CHIP  pkg 0402LF  page 237 : 1 = P3V3 ; 2 = SMB_HOST_CLK_BUF_ISO_3V3AUX_S_2
R4500  Q_RES  10K 1% EMPTY  pkg 0402LF  page 237 : 1 = P3V3 ; 2 = PU_CLK_BUF_ISO_EN
R4501  Q_RES  0 5% CHIP  pkg 0402LF  page 212 : 1 = CLK_GEN2_XTAL_IN_R ; 2 = CLK_GEN2_XTAL_IN
R4502  Q_RES  33.2 1% CHIP  pkg 0402LF  page 131 : 1 = SMB_HOST_3V3AUX_SCL_R4 ; 2 = SMB_HOST_3V3AUX_XDP_R_SCL
R4503  Q_RES  0 5% CHIP  pkg 0402LF  page 131 : 1 = SMB_HOST_3V3AUX_SDA_R4 ; 2 = SMB_HOST_3V3AUX_XDP_R_SDA
R4504  Q_RES  0 5% CHIP  pkg 0402LF  page 183 : 1 = SMB_SML1_PMBUS_3V3AUX_PCH_SDA ; 2 = SMB_SML1_PMBUS_3V3AUX_PCH_SDA_1
R4505  Q_RES  33.2 1% CHIP  pkg 0402LF  page 183 : 1 = SMB_SML1_PMBUS_3V3AUX_PCH_SCL ; 2 = SMB_SML1_PMBUS_3V3AUX_PCH_SCL_1
R4506  Q_RES  33.2 1% CHIP  pkg 0402LF  page 240 : 1 = SMB_SML0_3V3AUX_SCL ; 2 = SMB_SML0_3V3AUX_SCL_R1
R4507  Q_RES  33.2 1% CHIP  pkg 0402LF  page 240 : 1 = SMB_SML0_3V3AUX_SDA ; 2 = SMB_SML0_3V3AUX_SDA_R1
R4508  Q_RES  33.2 1% CHIP  pkg 0402LF  page 240 : 1 = SMB_1_PLD_3V3AUX_SCL ; 2 = SMB_1_PLD_3V3AUX_SCL_R3
R4509  Q_RES  33.2 1% CHIP  pkg 0402LF  page 240 : 1 = SMB_1_PLD_3V3AUX_SDA ; 2 = SMB_1_PLD_3V3AUX_SDA_R3
R4510  Q_RES  33.2 1% CHIP  pkg 0402LF  page 241 : 1 = SMB_HOST_3V3AUX_SCL ; 2 = SMB_HOST_3V3AUX_SCL_R4
R4511  Q_RES  0 5% CHIP  pkg 0402LF  page 241 : 1 = SMB_HOST_3V3AUX_SDA ; 2 = SMB_HOST_3V3AUX_SDA_R4
R4512  Q_RES  33.2 1% CHIP  pkg 0402LF  page 241 : 1 = SMB_HOST_3V3AUX_SCL ; 2 = SMB_HOST_3V3AUX_SCL_R5
R4513  Q_RES  0 5% CHIP  pkg 0402LF  page 241 : 1 = SMB_HOST_3V3AUX_SDA ; 2 = SMB_HOST_3V3AUX_SDA_R5
R4514  Q_RES  4.7K 1% EMPTY  pkg 0402LF  page 212 : 1 = CLK_GEN2_GPU_FPGA_OE_R2_N ; 2 = GND
R4515  Q_RES  100K 1% CHIP  pkg 0402LF  page 151 : 1 = P3V3_AUX ; 2 = UART_BMC_BIC_RX
R4516  Q_RES  10K 1% CHIP  pkg 0402LF  page 206 : 1 = P3V3 ; 2 = CLK_SWB_OE_N
